(kicad_pcb
	(version 20260206)
	(generator "pcbnew")
	(generator_version "10.0")
	(general
		(thickness 1.6)
		(legacy_teardrops no)
	)
	(paper "A4")
	(title_block
		(title "fcb — Lightning_FCB_BRD.brd")
		(comment 1 "Lightning (Wiwynn / Facebook NVMe JBOF) / footprints 418-425 of 495")
	)
	(layers
		(0 "F.Cu" signal "TOP")
		(4 "In1.Cu" signal "L2GND")
		(6 "In2.Cu" signal "L3VCC")
		(2 "B.Cu" signal "BOTTOM")
		(9 "F.Adhes" user "F.Adhesive")
		(11 "B.Adhes" user "B.Adhesive")
		(13 "F.Paste" user "Package Geometry/Pastemask Top")
		(15 "B.Paste" user "Package Geometry/Pastemask Bottom")
		(5 "F.SilkS" user "Ref Des/Silkscreen Top")
		(7 "B.SilkS" user "Ref Des/Silkscreen Bottom")
		(1 "F.Mask" user "Board Geometry/Soldermask Top")
		(3 "B.Mask" user "Board Geometry/Soldermask Bottom")
		(17 "Dwgs.User" user "User.Drawings")
		(19 "Cmts.User" user "User.Comments")
		(21 "Eco1.User" user "User.Eco1")
		(23 "Eco2.User" user "User.Eco2")
		(25 "Edge.Cuts" user "Board Geometry/Outline")
		(27 "Margin" user)
		(31 "F.CrtYd" user "Package Geometry/Place Bound Top")
		(29 "B.CrtYd" user "Package Geometry/Place Bound Bottom")
		(35 "F.Fab" user "Ref Des/Assembly Top")
		(33 "B.Fab" user "Ref Des/Assembly Bottom")
	)
	(footprint ""
		(layer "F.Cu")
		(at 34.741866 -137.508234 180)
		(property "Reference" "PR105"
			(at 0 0 180)
			(layer "F.SilkS")
			(hide yes)
			(effects
				(font
					(size 1.27 1.27)
				)
			)
		)
		(property "Value" "2K7R2F-GP"
			(at 0.064008 -3.993896 180)
			(unlocked yes)
			(layer "F.Fab")
			(hide yes)
			(effects
				(font
					(size 1.016 1.016)
					(thickness 0.1524)
				)
			)
		)
		(property "Device Type" "R402H16"
			(at 0.064008 -5.517896 180)
			(unlocked yes)
			(layer "F.Fab")
			(hide yes)
			(effects
				(font
					(size 1.016 1.016)
					(thickness 0.1524)
				)
			)
		)
		(duplicate_pad_numbers_are_jumpers no)
		(fp_line
			(start 0.508 -0.9398)
			(end -0.508 -0.9398)
			(stroke
				(width 0.1524)
				(type default)
			)
			(layer "F.SilkS")
		)
		(fp_line
			(start -0.508 -0.9398)
			(end -0.508 0.9398)
			(stroke
				(width 0.1524)
				(type default)
			)
			(layer "F.SilkS")
		)
		(fp_rect
			(start -0.508 0.9398)
			(end 0.508 -0.9398)
			(stroke
				(width 0)
				(type default)
			)
			(fill no)
			(layer "F.CrtYd")
		)
		(fp_rect
			(start -0.508 0.9398)
			(end 0.508 -0.9398)
			(stroke
				(width 0)
				(type default)
			)
			(fill no)
			(layer "F.Fab")
		)
		(pad "1" smd custom
			(at 0 -0.4445 180)
			(size 0.1397 0.1397)
			(layers "F.Cu" "F.Mask" "F.Paste")
			(net "P12VL")
			(options
				(clearance outline)
				(anchor circle)
			)
			(primitives
				(gr_poly
					(pts
						(arc
							(start -0.1778 -0.2794)
							(mid -0.249642 -0.249642)
							(end -0.2794 -0.1778)
						)
						(arc
							(start -0.2794 0.1778)
							(mid -0.249642 0.249642)
							(end -0.1778 0.2794)
						)
						(arc
							(start 0.1778 0.2794)
							(mid 0.249642 0.249642)
							(end 0.2794 0.1778)
						)
						(arc
							(start 0.2794 -0.1778)
							(mid 0.249642 -0.249642)
							(end 0.1778 -0.2794)
						)
					)
					(width 0)
					(fill yes)
				)
			)
		)
		(pad "2" smd custom
			(at 0 0.4445 180)
			(size 0.1397 0.1397)
			(layers "F.Cu" "F.Mask" "F.Paste")
			(net "P12VL_2490_PG")
			(options
				(clearance outline)
				(anchor circle)
			)
			(primitives
				(gr_poly
					(pts
						(arc
							(start -0.1778 -0.2794)
							(mid -0.249642 -0.249642)
							(end -0.2794 -0.1778)
						)
						(arc
							(start -0.2794 0.1778)
							(mid -0.249642 0.249642)
							(end -0.1778 0.2794)
						)
						(arc
							(start 0.1778 0.2794)
							(mid 0.249642 0.249642)
							(end 0.2794 0.1778)
						)
						(arc
							(start 0.2794 -0.1778)
							(mid 0.249642 -0.249642)
							(end 0.1778 -0.2794)
						)
					)
					(width 0)
					(fill yes)
				)
			)
		)
	)
	(footprint ""
		(layer "F.Cu")
		(at 40.005 -371.475 -90)
		(property "Reference" "C255"
			(at 0 0 270)
			(layer "F.SilkS")
			(hide yes)
			(effects
				(font
					(size 1.27 1.27)
				)
			)
		)
		(property "Value" "SCD1U25V3KX-LL-GP"
			(at 0 -2.8194 270)
			(unlocked yes)
			(layer "F.Fab")
			(hide yes)
			(effects
				(font
					(size 1.016 1.016)
					(thickness 0.1524)
				)
			)
		)
		(property "Device Type" "C603H36"
			(at 0 -4.3434 270)
			(unlocked yes)
			(layer "F.Fab")
			(hide yes)
			(effects
				(font
					(size 1.016 1.016)
					(thickness 0.1524)
				)
			)
		)
		(duplicate_pad_numbers_are_jumpers no)
		(fp_line
			(start 0.508 0)
			(end -0.508 0)
			(stroke
				(width 0.2032)
				(type default)
			)
			(layer "F.SilkS")
		)
		(fp_rect
			(start -0.5842 1.3335)
			(end 0.5842 -1.3335)
			(stroke
				(width 0)
				(type default)
			)
			(fill no)
			(layer "F.CrtYd")
		)
		(fp_rect
			(start -0.5842 1.3335)
			(end 0.5842 -1.3335)
			(stroke
				(width 0)
				(type default)
			)
			(fill no)
			(layer "F.Fab")
		)
		(pad "1" smd custom
			(at 0 -0.762 270)
			(size 0.2159 0.2159)
			(layers "F.Cu" "F.Mask" "F.Paste")
			(net "ADM1276_LATCH_B")
			(options
				(clearance outline)
				(anchor circle)
			)
			(primitives
				(gr_poly
					(pts
						(arc
							(start -0.3302 -0.4318)
							(mid -0.402042 -0.402042)
							(end -0.4318 -0.3302)
						)
						(arc
							(start -0.4318 0.3302)
							(mid -0.402042 0.402042)
							(end -0.3302 0.4318)
						)
						(arc
							(start 0.3302 0.4318)
							(mid 0.402042 0.402042)
							(end 0.4318 0.3302)
						)
						(arc
							(start 0.4318 -0.3302)
							(mid 0.402042 -0.402042)
							(end 0.3302 -0.4318)
						)
					)
					(width 0)
					(fill yes)
				)
			)
		)
		(pad "2" smd custom
			(at 0 0.762 270)
			(size 0.2159 0.2159)
			(layers "F.Cu" "F.Mask" "F.Paste")
			(net "GND")
			(options
				(clearance outline)
				(anchor circle)
			)
			(primitives
				(gr_poly
					(pts
						(arc
							(start -0.3302 -0.4318)
							(mid -0.402042 -0.402042)
							(end -0.4318 -0.3302)
						)
						(arc
							(start -0.4318 0.3302)
							(mid -0.402042 0.402042)
							(end -0.3302 0.4318)
						)
						(arc
							(start 0.3302 0.4318)
							(mid 0.402042 0.402042)
							(end 0.4318 0.3302)
						)
						(arc
							(start 0.4318 -0.3302)
							(mid 0.402042 -0.402042)
							(end 0.3302 -0.4318)
						)
					)
					(width 0)
					(fill yes)
				)
			)
		)
	)
	(footprint ""
		(layer "F.Cu")
		(at 32.78251 -171.677076)
		(property "Reference" "C12"
			(at 0 0 0)
			(layer "F.SilkS")
			(hide yes)
			(effects
				(font
					(size 1.27 1.27)
				)
			)
		)
		(property "Value" "SC1U16V3KX-5GP"
			(at 0 -2.8194 0)
			(unlocked yes)
			(layer "F.Fab")
			(hide yes)
			(effects
				(font
					(size 1.016 1.016)
					(thickness 0.1524)
				)
			)
		)
		(property "Device Type" "C603H36"
			(at 0 -4.3434 0)
			(unlocked yes)
			(layer "F.Fab")
			(hide yes)
			(effects
				(font
					(size 1.016 1.016)
					(thickness 0.1524)
				)
			)
		)
		(duplicate_pad_numbers_are_jumpers no)
		(fp_line
			(start 0.508 0)
			(end -0.508 0)
			(stroke
				(width 0.2032)
				(type default)
			)
			(layer "F.SilkS")
		)
		(fp_rect
			(start -0.5842 1.3335)
			(end 0.5842 -1.3335)
			(stroke
				(width 0)
				(type default)
			)
			(fill no)
			(layer "F.CrtYd")
		)
		(fp_rect
			(start -0.5842 1.3335)
			(end 0.5842 -1.3335)
			(stroke
				(width 0)
				(type default)
			)
			(fill no)
			(layer "F.Fab")
		)
		(pad "1" smd custom
			(at 0 -0.762)
			(size 0.2159 0.2159)
			(layers "F.Cu" "F.Mask" "F.Paste")
			(net "P3V3")
			(options
				(clearance outline)
				(anchor circle)
			)
			(primitives
				(gr_poly
					(pts
						(arc
							(start -0.3302 -0.4318)
							(mid -0.402042 -0.402042)
							(end -0.4318 -0.3302)
						)
						(arc
							(start -0.4318 0.3302)
							(mid -0.402042 0.402042)
							(end -0.3302 0.4318)
						)
						(arc
							(start 0.3302 0.4318)
							(mid 0.402042 0.402042)
							(end 0.4318 0.3302)
						)
						(arc
							(start 0.4318 -0.3302)
							(mid 0.402042 -0.402042)
							(end 0.3302 -0.4318)
						)
					)
					(width 0)
					(fill yes)
				)
			)
		)
		(pad "2" smd custom
			(at 0 0.762)
			(size 0.2159 0.2159)
			(layers "F.Cu" "F.Mask" "F.Paste")
			(net "GND")
			(options
				(clearance outline)
				(anchor circle)
			)
			(primitives
				(gr_poly
					(pts
						(arc
							(start -0.3302 -0.4318)
							(mid -0.402042 -0.402042)
							(end -0.4318 -0.3302)
						)
						(arc
							(start -0.4318 0.3302)
							(mid -0.402042 0.402042)
							(end -0.3302 0.4318)
						)
						(arc
							(start 0.3302 0.4318)
							(mid 0.402042 0.402042)
							(end 0.4318 0.3302)
						)
						(arc
							(start 0.4318 -0.3302)
							(mid 0.402042 -0.402042)
							(end 0.3302 -0.4318)
						)
					)
					(width 0)
					(fill yes)
				)
			)
		)
	)
	(footprint ""
		(layer "F.Cu")
		(at 35.3314 -254.3556 180)
		(property "Reference" "R107"
			(at 0 0 180)
			(layer "F.SilkS")
			(hide yes)
			(effects
				(font
					(size 1.27 1.27)
				)
			)
		)
		(property "Value" "0R2J-2-GP"
			(at 0.064008 -3.993896 180)
			(unlocked yes)
			(layer "F.Fab")
			(hide yes)
			(effects
				(font
					(size 1.016 1.016)
					(thickness 0.1524)
				)
			)
		)
		(property "Device Type" "R402H16"
			(at 0.064008 -5.517896 180)
			(unlocked yes)
			(layer "F.Fab")
			(hide yes)
			(effects
				(font
					(size 1.016 1.016)
					(thickness 0.1524)
				)
			)
		)
		(duplicate_pad_numbers_are_jumpers no)
		(fp_line
			(start 0.508 -0.9398)
			(end -0.508 -0.9398)
			(stroke
				(width 0.1524)
				(type default)
			)
			(layer "F.SilkS")
		)
		(fp_line
			(start -0.508 -0.9398)
			(end -0.508 0.9398)
			(stroke
				(width 0.1524)
				(type default)
			)
			(layer "F.SilkS")
		)
		(fp_rect
			(start -0.508 0.9398)
			(end 0.508 -0.9398)
			(stroke
				(width 0)
				(type default)
			)
			(fill no)
			(layer "F.CrtYd")
		)
		(fp_rect
			(start -0.508 0.9398)
			(end 0.508 -0.9398)
			(stroke
				(width 0)
				(type default)
			)
			(fill no)
			(layer "F.Fab")
		)
		(pad "1" smd custom
			(at 0 -0.4445 180)
			(size 0.1397 0.1397)
			(layers "F.Cu" "F.Mask" "F.Paste")
			(net "I2C_C_SCL_LEDDRV")
			(options
				(clearance outline)
				(anchor circle)
			)
			(primitives
				(gr_poly
					(pts
						(arc
							(start -0.1778 -0.2794)
							(mid -0.249642 -0.249642)
							(end -0.2794 -0.1778)
						)
						(arc
							(start -0.2794 0.1778)
							(mid -0.249642 0.249642)
							(end -0.1778 0.2794)
						)
						(arc
							(start 0.1778 0.2794)
							(mid 0.249642 0.249642)
							(end 0.2794 0.1778)
						)
						(arc
							(start 0.2794 -0.1778)
							(mid 0.249642 -0.249642)
							(end 0.1778 -0.2794)
						)
					)
					(width 0)
					(fill yes)
				)
			)
		)
		(pad "2" smd custom
			(at 0 0.4445 180)
			(size 0.1397 0.1397)
			(layers "F.Cu" "F.Mask" "F.Paste")
			(net "I2C_C_SCL")
			(options
				(clearance outline)
				(anchor circle)
			)
			(primitives
				(gr_poly
					(pts
						(arc
							(start -0.1778 -0.2794)
							(mid -0.249642 -0.249642)
							(end -0.2794 -0.1778)
						)
						(arc
							(start -0.2794 0.1778)
							(mid -0.249642 0.249642)
							(end -0.1778 0.2794)
						)
						(arc
							(start 0.1778 0.2794)
							(mid 0.249642 0.249642)
							(end 0.2794 0.1778)
						)
						(arc
							(start 0.2794 -0.1778)
							(mid 0.249642 -0.249642)
							(end 0.1778 -0.2794)
						)
					)
					(width 0)
					(fill yes)
				)
			)
		)
	)
	(footprint ""
		(layer "F.Cu")
		(at 29.1338 -153.289 90)
		(property "Reference" "C8"
			(at 0 0 90)
			(layer "F.SilkS")
			(hide yes)
			(effects
				(font
					(size 1.27 1.27)
				)
			)
		)
		(property "Value" "SC2200P50V2KX-2GP"
			(at 1.1811 -2.7051 90)
			(unlocked yes)
			(layer "F.Fab")
			(hide yes)
			(effects
				(font
					(size 1.016 1.016)
					(thickness 0.1524)
				)
			)
		)
		(property "Device Type" "C402H22"
			(at 1.1811 -4.2291 90)
			(unlocked yes)
			(layer "F.Fab")
			(hide yes)
			(effects
				(font
					(size 1.016 1.016)
					(thickness 0.1524)
				)
			)
		)
		(duplicate_pad_numbers_are_jumpers no)
		(fp_rect
			(start -0.4318 0.9525)
			(end 0.4318 -0.9525)
			(stroke
				(width 0)
				(type default)
			)
			(fill no)
			(layer "F.CrtYd")
		)
		(fp_rect
			(start -0.4318 0.9525)
			(end 0.4318 -0.9525)
			(stroke
				(width 0)
				(type default)
			)
			(fill no)
			(layer "F.Fab")
		)
		(pad "1" smd custom
			(at 0 -0.4445 90)
			(size 0.1524 0.1524)
			(layers "F.Cu" "F.Mask" "F.Paste")
			(net "NCT7904_D2+")
			(options
				(clearance outline)
				(anchor circle)
			)
			(primitives
				(gr_poly
					(pts
						(arc
							(start 0.3048 -0.2032)
							(mid 0.275042 -0.275042)
							(end 0.2032 -0.3048)
						)
						(arc
							(start -0.2032 -0.3048)
							(mid -0.275042 -0.275042)
							(end -0.3048 -0.2032)
						)
						(arc
							(start -0.3048 0.2032)
							(mid -0.275042 0.275042)
							(end -0.2032 0.3048)
						)
						(arc
							(start 0.2032 0.3048)
							(mid 0.275042 0.275042)
							(end 0.3048 0.2032)
						)
					)
					(width 0)
					(fill yes)
				)
			)
		)
		(pad "2" smd custom
			(at 0 0.4445 90)
			(size 0.1524 0.1524)
			(layers "F.Cu" "F.Mask" "F.Paste")
			(net "NCT7904_D2-")
			(options
				(clearance outline)
				(anchor circle)
			)
			(primitives
				(gr_poly
					(pts
						(arc
							(start 0.3048 -0.2032)
							(mid 0.275042 -0.275042)
							(end 0.2032 -0.3048)
						)
						(arc
							(start -0.2032 -0.3048)
							(mid -0.275042 -0.275042)
							(end -0.3048 -0.2032)
						)
						(arc
							(start -0.3048 0.2032)
							(mid -0.275042 0.275042)
							(end -0.2032 0.3048)
						)
						(arc
							(start 0.2032 0.3048)
							(mid 0.275042 0.275042)
							(end 0.3048 0.2032)
						)
					)
					(width 0)
					(fill yes)
				)
			)
		)
	)
	(footprint ""
		(layer "F.Cu")
		(at 36.195 -176.657 -90)
		(property "Reference" "C256"
			(at 0 0 270)
			(layer "F.SilkS")
			(hide yes)
			(effects
				(font
					(size 1.27 1.27)
				)
			)
		)
		(property "Value" "SCD1U16V2KX-3GP"
			(at 1.1811 -2.7051 270)
			(unlocked yes)
			(layer "F.Fab")
			(hide yes)
			(effects
				(font
					(size 1.016 1.016)
					(thickness 0.1524)
				)
			)
		)
		(property "Device Type" "C402H22"
			(at 1.1811 -4.2291 270)
			(unlocked yes)
			(layer "F.Fab")
			(hide yes)
			(effects
				(font
					(size 1.016 1.016)
					(thickness 0.1524)
				)
			)
		)
		(duplicate_pad_numbers_are_jumpers no)
		(fp_rect
			(start -0.4318 0.9525)
			(end 0.4318 -0.9525)
			(stroke
				(width 0)
				(type default)
			)
			(fill no)
			(layer "F.CrtYd")
		)
		(fp_rect
			(start -0.4318 0.9525)
			(end 0.4318 -0.9525)
			(stroke
				(width 0)
				(type default)
			)
			(fill no)
			(layer "F.Fab")
		)
		(pad "1" smd custom
			(at 0 -0.4445 270)
			(size 0.1524 0.1524)
			(layers "F.Cu" "F.Mask" "F.Paste")
			(net "TEMP_ALM#_IN_D")
			(options
				(clearance outline)
				(anchor circle)
			)
			(primitives
				(gr_poly
					(pts
						(arc
							(start 0.3048 -0.2032)
							(mid 0.275042 -0.275042)
							(end 0.2032 -0.3048)
						)
						(arc
							(start -0.2032 -0.3048)
							(mid -0.275042 -0.275042)
							(end -0.3048 -0.2032)
						)
						(arc
							(start -0.3048 0.2032)
							(mid -0.275042 0.275042)
							(end -0.2032 0.3048)
						)
						(arc
							(start 0.2032 0.3048)
							(mid 0.275042 0.275042)
							(end 0.3048 0.2032)
						)
					)
					(width 0)
					(fill yes)
				)
			)
		)
		(pad "2" smd custom
			(at 0 0.4445 270)
			(size 0.1524 0.1524)
			(layers "F.Cu" "F.Mask" "F.Paste")
			(net "GND")
			(options
				(clearance outline)
				(anchor circle)
			)
			(primitives
				(gr_poly
					(pts
						(arc
							(start 0.3048 -0.2032)
							(mid 0.275042 -0.275042)
							(end 0.2032 -0.3048)
						)
						(arc
							(start -0.2032 -0.3048)
							(mid -0.275042 -0.275042)
							(end -0.3048 -0.2032)
						)
						(arc
							(start -0.3048 0.2032)
							(mid -0.275042 0.275042)
							(end -0.2032 0.3048)
						)
						(arc
							(start 0.2032 0.3048)
							(mid 0.275042 0.275042)
							(end 0.3048 0.2032)
						)
					)
					(width 0)
					(fill yes)
				)
			)
		)
	)
	(footprint ""
		(layer "F.Cu")
		(at 13.081 -448.2338 90)
		(property "Reference" "R101"
			(at 0 0 90)
			(layer "F.SilkS")
			(hide yes)
			(effects
				(font
					(size 1.27 1.27)
				)
			)
		)
		(property "Value" "27KR3F-GP"
			(at -0.0254 -2.5146 90)
			(unlocked yes)
			(layer "F.Fab")
			(hide yes)
			(effects
				(font
					(size 1.016 1.016)
					(thickness 0.1524)
				)
			)
		)
		(property "Device Type" "R603H22"
			(at -0.0254 -4.0386 90)
			(unlocked yes)
			(layer "F.Fab")
			(hide yes)
			(effects
				(font
					(size 1.016 1.016)
					(thickness 0.1524)
				)
			)
		)
		(duplicate_pad_numbers_are_jumpers no)
		(fp_line
			(start 0.2032 0)
			(end 0.4826 0)
			(stroke
				(width 0.2032)
				(type default)
			)
			(layer "F.SilkS")
		)
		(fp_line
			(start -0.4826 0)
			(end -0.2032 0)
			(stroke
				(width 0.2032)
				(type default)
			)
			(layer "F.SilkS")
		)
		(fp_rect
			(start -0.5842 1.3335)
			(end 0.5842 -1.3335)
			(stroke
				(width 0)
				(type default)
			)
			(fill no)
			(layer "F.CrtYd")
		)
		(fp_rect
			(start -0.5842 1.3335)
			(end 0.5842 -1.3335)
			(stroke
				(width 0)
				(type default)
			)
			(fill no)
			(layer "F.Fab")
		)
		(pad "1" smd custom
			(at 0 -0.762 90)
			(size 0.2159 0.2159)
			(layers "F.Cu" "F.Mask" "F.Paste")
			(net "FAN_TACH2")
			(options
				(clearance outline)
				(anchor circle)
			)
			(primitives
				(gr_poly
					(pts
						(arc
							(start -0.3302 -0.4318)
							(mid -0.402042 -0.402042)
							(end -0.4318 -0.3302)
						)
						(arc
							(start -0.4318 0.3302)
							(mid -0.402042 0.402042)
							(end -0.3302 0.4318)
						)
						(arc
							(start 0.3302 0.4318)
							(mid 0.402042 0.402042)
							(end 0.4318 0.3302)
						)
						(arc
							(start 0.4318 -0.3302)
							(mid 0.402042 -0.402042)
							(end 0.3302 -0.4318)
						)
					)
					(width 0)
					(fill yes)
				)
			)
		)
		(pad "2" smd custom
			(at 0 0.762 90)
			(size 0.2159 0.2159)
			(layers "F.Cu" "F.Mask" "F.Paste")
			(net "FANIN_2")
			(options
				(clearance outline)
				(anchor circle)
			)
			(primitives
				(gr_poly
					(pts
						(arc
							(start -0.3302 -0.4318)
							(mid -0.402042 -0.402042)
							(end -0.4318 -0.3302)
						)
						(arc
							(start -0.4318 0.3302)
							(mid -0.402042 0.402042)
							(end -0.3302 0.4318)
						)
						(arc
							(start 0.3302 0.4318)
							(mid 0.402042 0.402042)
							(end 0.4318 0.3302)
						)
						(arc
							(start 0.4318 -0.3302)
							(mid 0.402042 -0.402042)
							(end 0.3302 -0.4318)
						)
					)
					(width 0)
					(fill yes)
				)
			)
		)
	)
	(footprint ""
		(layer "F.Cu")
		(at 28.321 -352.425 -90)
		(property "Reference" "C260"
			(at 0 0 270)
			(layer "F.SilkS")
			(hide yes)
			(effects
				(font
					(size 1.27 1.27)
				)
			)
		)
		(property "Value" "SC10U25V6KX-1GP"
			(at -0.0762 -5.1308 270)
			(unlocked yes)
			(layer "F.Fab")
			(hide yes)
			(effects
				(font
					(size 1.016 1.016)
					(thickness 0.1524)
				)
			)
		)
		(property "Device Type" "C1206H71"
			(at -0.127 -6.6548 270)
			(unlocked yes)
			(layer "F.Fab")
			(hide yes)
			(effects
				(font
					(size 1.016 1.016)
					(thickness 0.1524)
				)
			)
		)
		(duplicate_pad_numbers_are_jumpers no)
		(fp_line
			(start -1.016 2.2352)
			(end -1.016 0.8382)
			(stroke
				(width 0.1524)
				(type default)
			)
			(layer "F.SilkS")
		)
		(fp_line
			(start 1.016 2.2352)
			(end -1.016 2.2352)
			(stroke
				(width 0.1524)
				(type default)
			)
			(layer "F.SilkS")
		)
		(fp_line
			(start 1.016 0.8382)
			(end 1.016 2.2352)
			(stroke
				(width 0.1524)
				(type default)
			)
			(layer "F.SilkS")
		)
		(fp_line
			(start -1.016 -0.8382)
			(end -1.016 -2.2352)
			(stroke
				(width 0.1524)
				(type default)
			)
			(layer "F.SilkS")
		)
		(fp_line
			(start -1.016 -2.2352)
			(end 1.016 -2.2352)
			(stroke
				(width 0.1524)
				(type default)
			)
			(layer "F.SilkS")
		)
		(fp_line
			(start 1.016 -2.2352)
			(end 1.016 -0.8382)
			(stroke
				(width 0.1524)
				(type default)
			)
			(layer "F.SilkS")
		)
		(fp_rect
			(start -1.0922 2.3114)
			(end 1.0922 -2.3114)
			(stroke
				(width 0)
				(type default)
			)
			(fill no)
			(layer "F.CrtYd")
		)
		(fp_poly
			(pts
				(xy 1.0922 -2.3114) (xy 1.0922 2.3114) (xy -1.0922 2.3114) (xy -1.0922 -2.3114)
			)
			(stroke
				(width 0)
				(type default)
			)
			(fill no)
			(layer "F.Fab")
		)
		(pad "1" smd rect
			(at 0 -1.397 270)
			(size 1.651 1.27)
			(layers "F.Cu" "F.Mask" "F.Paste")
			(net "OTP_RETRY_G")
		)
		(pad "2" smd rect
			(at 0 1.397 270)
			(size 1.651 1.27)
			(layers "F.Cu" "F.Mask" "F.Paste")
			(net "GND")
		)
	)
)
